# T6G (Grand Teton) — schematic netlist excerpt (pin names and nets, part order shuffled) for the footprints in the layout excerpt that follows; sources: Cadence DE-HDL packaged netlist, KiCad conversion of 04192023_DAF0TMB3IC0_F0TG_MB_C_brd_V02_OCP.brd

PC397_2  Q_CAP  22UF 4V 20% X6S  pkg C0805  page 218 : A = PVDDCR_CPU1_P1 ; B = GND
PC529_1  Q_CAP  22UF 4V 20% X6S  pkg C0805  page 225 : A = PVDD11_S3_P1 ; B = GND
PR172  Q_RES  0 5% CHIP  pkg 0402LF  page 210 : A = SVID_PVDDCR_CPU0_P1_SVTI ; B = SVID_PVDDCR_CPU0_P1_SVTI_R
C6743  Q_CAP_DIFFBUS  DIFF BUS_0.22UF 6.3V 20% X6S  pkg C0201  page 352 : \1\ = P5E_CPU1_P3_TX_BUF_C_DP<9> ; \2\ = P5E_CPU1_P3_TX_BUF_DP<9>

(kicad_pcb
	(version 20260206)
	(generator "pcbnew")
	(generator_version "10.0")
	(general
		(thickness 1.6)
		(legacy_teardrops no)
	)
	(paper "A4")
	(title_block
		(title "04192023_DAF0TMB3IC0_F0TG_MB_C_brd_V02_OCP.brd")
		(comment 1 "Grand Teton / footprints 8287-8290 of 8354")
	)
	(layers
		(0 "F.Cu" signal "TOP")
		(4 "In1.Cu" signal "GND")
		(6 "In2.Cu" signal "IN1")
		(8 "In3.Cu" signal "GND1")
		(10 "In4.Cu" signal "IN2")
		(12 "In5.Cu" signal "GND2")
		(14 "In6.Cu" signal "IN3")
		(16 "In7.Cu" signal "GND3")
		(18 "In8.Cu" signal "VCC")
		(20 "In9.Cu" signal "VCC1")
		(22 "In10.Cu" signal "GND4")
		(24 "In11.Cu" signal "IN4")
		(26 "In12.Cu" signal "GND5")
		(28 "In13.Cu" signal "IN5")
		(30 "In14.Cu" signal "GND6")
		(32 "In15.Cu" signal "IN6")
		(34 "In16.Cu" signal "GND7")
		(2 "B.Cu" signal "BOTTOM")
		(9 "F.Adhes" user "F.Adhesive")
		(11 "B.Adhes" user "B.Adhesive")
		(13 "F.Paste" user "Package Geometry/Pastemask Top")
		(15 "B.Paste" user "Package Geometry/Pastemask Bottom")
		(5 "F.SilkS" user "Ref Des/Silkscreen Top")
		(7 "B.SilkS" user "Ref Des/Silkscreen Bottom")
		(1 "F.Mask" user "Board Geometry/Soldermask Top")
		(3 "B.Mask" user "Board Geometry/Soldermask Bottom")
		(17 "Dwgs.User" user "User.Drawings")
		(19 "Cmts.User" user "User.Comments")
		(21 "Eco1.User" user "User.Eco1")
		(23 "Eco2.User" user "User.Eco2")
		(25 "Edge.Cuts" user "Board Geometry/Outline")
		(27 "Margin" user)
		(31 "F.CrtYd" user "Package Geometry/Place Bound Top")
		(29 "B.CrtYd" user "Package Geometry/Place Bound Bottom")
		(35 "F.Fab" user "Ref Des/Assembly Top")
		(33 "B.Fab" user "Ref Des/Assembly Bottom")
	)
	(footprint ""
		(layer "B.Cu")
		(at 90.209878 -149.96541 180)
		(property "Reference" "PR172"
			(at 0 0 0)
			(layer "B.SilkS")
			(hide yes)
			(effects
				(font
					(size 1.27 1.27)
				)
				(justify mirror)
			)
		)
		(property "Value" ""
			(at 0 0 0)
			(layer "B.Fab")
			(effects
				(font
					(size 1.27 1.27)
				)
				(justify mirror)
			)
		)
		(duplicate_pad_numbers_are_jumpers no)
		(fp_line
			(start 0.7874 0.4064)
			(end 0.7874 -0.4064)
			(stroke
				(width 0.1524)
				(type default)
			)
			(layer "B.SilkS")
		)
		(fp_line
			(start 0.7874 -0.4064)
			(end -0.7874 -0.4064)
			(stroke
				(width 0.1524)
				(type default)
			)
			(layer "B.SilkS")
		)
		(fp_line
			(start -0.7874 0.4064)
			(end 0.7874 0.4064)
			(stroke
				(width 0.1524)
				(type default)
			)
			(layer "B.SilkS")
		)
		(fp_line
			(start -0.7874 -0.4064)
			(end -0.7874 0.4064)
			(stroke
				(width 0.1524)
				(type default)
			)
			(layer "B.SilkS")
		)
		(fp_line
			(start 0.67945 0.3048)
			(end 0.67945 -0.305054)
			(stroke
				(width 0.1)
				(type default)
			)
			(layer "B.Fab")
		)
		(fp_line
			(start 0.67945 -0.305054)
			(end 0.12065 -0.305054)
			(stroke
				(width 0.1)
				(type default)
			)
			(layer "B.Fab")
		)
		(fp_line
			(start 0.12065 0.3048)
			(end 0.67945 0.3048)
			(stroke
				(width 0.1)
				(type default)
			)
			(layer "B.Fab")
		)
		(fp_line
			(start 0.12065 0.2794)
			(end 0.12065 0.3048)
			(stroke
				(width 0.1)
				(type default)
			)
			(layer "B.Fab")
		)
		(fp_line
			(start 0.12065 -0.2794)
			(end -0.12065 -0.2794)
			(stroke
				(width 0.1)
				(type default)
			)
			(layer "B.Fab")
		)
		(fp_line
			(start 0.12065 -0.305054)
			(end 0.12065 -0.2794)
			(stroke
				(width 0.1)
				(type default)
			)
			(layer "B.Fab")
		)
		(fp_line
			(start -0.120396 0.3048)
			(end -0.120396 0.2794)
			(stroke
				(width 0.1)
				(type default)
			)
			(layer "B.Fab")
		)
		(fp_line
			(start -0.120396 0.2794)
			(end 0.12065 0.2794)
			(stroke
				(width 0.1)
				(type default)
			)
			(layer "B.Fab")
		)
		(fp_line
			(start -0.12065 -0.2794)
			(end -0.12065 -0.3048)
			(stroke
				(width 0.1)
				(type default)
			)
			(layer "B.Fab")
		)
		(fp_line
			(start -0.12065 -0.3048)
			(end -0.67945 -0.3048)
			(stroke
				(width 0.1)
				(type default)
			)
			(layer "B.Fab")
		)
		(fp_line
			(start -0.67945 0.3048)
			(end -0.120396 0.3048)
			(stroke
				(width 0.1)
				(type default)
			)
			(layer "B.Fab")
		)
		(fp_line
			(start -0.67945 -0.3048)
			(end -0.67945 0.3048)
			(stroke
				(width 0.1)
				(type default)
			)
			(layer "B.Fab")
		)
		(pad "1" smd circle
			(at 0.40005 0)
			(size 0 0)
			(layers "B.Cu" "B.Mask" "B.Paste")
			(net "SVID_PVDDCR_CPU0_P1_SVTI")
		)
		(pad "2" smd circle
			(at -0.40005 0)
			(size 0 0)
			(layers "B.Cu" "B.Mask" "B.Paste")
			(net "SVID_PVDDCR_CPU0_P1_SVTI_R")
		)
	)
	(footprint ""
		(layer "B.Cu")
		(at 144.883886 -408.517344 90)
		(property "Reference" "C6743"
			(at 0 0 90)
			(layer "B.SilkS")
			(hide yes)
			(effects
				(font
					(size 1.27 1.27)
				)
				(justify mirror)
			)
		)
		(property "Value" ""
			(at 0 0 90)
			(layer "B.Fab")
			(effects
				(font
					(size 1.27 1.27)
				)
				(justify mirror)
			)
		)
		(duplicate_pad_numbers_are_jumpers no)
		(fp_line
			(start 0.299974 -0.150114)
			(end -0.299974 -0.150114)
			(stroke
				(width 0.1)
				(type default)
			)
			(layer "B.Fab")
		)
		(fp_line
			(start -0.299974 -0.150114)
			(end -0.299974 0.150114)
			(stroke
				(width 0.1)
				(type default)
			)
			(layer "B.Fab")
		)
		(fp_line
			(start 0.299974 0.150114)
			(end 0.299974 -0.150114)
			(stroke
				(width 0.1)
				(type default)
			)
			(layer "B.Fab")
		)
		(fp_line
			(start -0.299974 0.150114)
			(end 0.299974 0.150114)
			(stroke
				(width 0.1)
				(type default)
			)
			(layer "B.Fab")
		)
		(pad "1" smd rect
			(at 0.2667 0 270)
			(size 0.3048 0.381)
			(layers "B.Cu" "B.Mask" "B.Paste")
			(net "P5E_CPU1_P3_TX_BUF_C_DP<9>")
		)
		(pad "2" smd rect
			(at -0.2667 0 270)
			(size 0.3048 0.381)
			(layers "B.Cu" "B.Mask" "B.Paste")
			(net "P5E_CPU1_P3_TX_BUF_DP<9>")
		)
	)
	(footprint ""
		(layer "B.Cu")
		(at 83.269074 -326.315832 -90)
		(property "Reference" "PC397_2"
			(at 0 0 90)
			(layer "B.SilkS")
			(hide yes)
			(effects
				(font
					(size 1.27 1.27)
				)
				(justify mirror)
			)
		)
		(property "Value" ""
			(at 0 0 90)
			(layer "B.Fab")
			(effects
				(font
					(size 1.27 1.27)
				)
				(justify mirror)
			)
		)
		(duplicate_pad_numbers_are_jumpers no)
		(fp_line
			(start -1.524 0.762)
			(end 1.524 0.762)
			(stroke
				(width 0.1524)
				(type default)
			)
			(layer "B.SilkS")
		)
		(fp_line
			(start 1.524 0.762)
			(end 1.524 -0.762)
			(stroke
				(width 0.1524)
				(type default)
			)
			(layer "B.SilkS")
		)
		(fp_line
			(start -1.524 -0.762)
			(end -1.524 0.762)
			(stroke
				(width 0.1524)
				(type default)
			)
			(layer "B.SilkS")
		)
		(fp_line
			(start 1.524 -0.762)
			(end -1.524 -0.762)
			(stroke
				(width 0.1524)
				(type default)
			)
			(layer "B.SilkS")
		)
		(fp_line
			(start -1.1049 0.724916)
			(end -1.1049 -0.724916)
			(stroke
				(width 0.1)
				(type default)
			)
			(layer "B.Fab")
		)
		(fp_line
			(start 1.1049 0.724916)
			(end -1.1049 0.724916)
			(stroke
				(width 0.1)
				(type default)
			)
			(layer "B.Fab")
		)
		(fp_line
			(start -1.1049 -0.724916)
			(end 1.1049 -0.724916)
			(stroke
				(width 0.1)
				(type default)
			)
			(layer "B.Fab")
		)
		(fp_line
			(start 1.1049 -0.724916)
			(end 1.1049 0.724916)
			(stroke
				(width 0.1)
				(type default)
			)
			(layer "B.Fab")
		)
		(pad "1" smd rect
			(at 0.889 0 270)
			(size 1.016 1.27)
			(layers "B.Cu" "B.Mask" "B.Paste")
			(net "PVDDCR_CPU1_P1")
		)
		(pad "2" smd rect
			(at -0.889 0 270)
			(size 1.016 1.27)
			(layers "B.Cu" "B.Mask" "B.Paste")
			(net "GND")
		)
	)
	(footprint ""
		(layer "B.Cu")
		(at 172.352208 -342.261952 -90)
		(property "Reference" "PC529_1"
			(at 0 0 90)
			(layer "B.SilkS")
			(hide yes)
			(effects
				(font
					(size 1.27 1.27)
				)
				(justify mirror)
			)
		)
		(property "Value" ""
			(at 0 0 90)
			(layer "B.Fab")
			(effects
				(font
					(size 1.27 1.27)
				)
				(justify mirror)
			)
		)
		(duplicate_pad_numbers_are_jumpers no)
		(fp_line
			(start -1.524 0.762)
			(end 1.524 0.762)
			(stroke
				(width 0.1524)
				(type default)
			)
			(layer "B.SilkS")
		)
		(fp_line
			(start 1.524 0.762)
			(end 1.524 -0.762)
			(stroke
				(width 0.1524)
				(type default)
			)
			(layer "B.SilkS")
		)
		(fp_line
			(start -1.524 -0.762)
			(end -1.524 0.762)
			(stroke
				(width 0.1524)
				(type default)
			)
			(layer "B.SilkS")
		)
		(fp_line
			(start 1.524 -0.762)
			(end -1.524 -0.762)
			(stroke
				(width 0.1524)
				(type default)
			)
			(layer "B.SilkS")
		)
		(fp_line
			(start -1.1049 0.724916)
			(end -1.1049 -0.724916)
			(stroke
				(width 0.1)
				(type default)
			)
			(layer "B.Fab")
		)
		(fp_line
			(start 1.1049 0.724916)
			(end -1.1049 0.724916)
			(stroke
				(width 0.1)
				(type default)
			)
			(layer "B.Fab")
		)
		(fp_line
			(start -1.1049 -0.724916)
			(end 1.1049 -0.724916)
			(stroke
				(width 0.1)
				(type default)
			)
			(layer "B.Fab")
		)
		(fp_line
			(start 1.1049 -0.724916)
			(end 1.1049 0.724916)
			(stroke
				(width 0.1)
				(type default)
			)
			(layer "B.Fab")
		)
		(pad "1" smd rect
			(at 0.889 0 270)
			(size 1.016 1.27)
			(layers "B.Cu" "B.Mask" "B.Paste")
			(net "PVDD11_S3_P1")
		)
		(pad "2" smd rect
			(at -0.889 0 270)
			(size 1.016 1.27)
			(layers "B.Cu" "B.Mask" "B.Paste")
			(net "GND")
		)
	)
)
